(kicad_pcb
	(version 20260206)
	(generator "pcbnew")
	(generator_version "10.0")
	(general
		(thickness 1.6)
		(legacy_teardrops no)
	)
	(paper "A4")
	(title_block
		(title "v1-chassis-manager — T6M_CM_d_v01_1031_1645.brd")
		(comment 1 "Open CloudServer (Microsoft) / footprints 625-632 of 2512")
	)
	(layers
		(0 "F.Cu" signal "TOP")
		(4 "In1.Cu" signal "GND1")
		(6 "In2.Cu" signal "IN1")
		(8 "In3.Cu" signal "VCC1")
		(10 "In4.Cu" signal "VCC2")
		(12 "In5.Cu" signal "GND2")
		(14 "In6.Cu" signal "IN2")
		(16 "In7.Cu" signal "IN3")
		(18 "In8.Cu" signal "GND3")
		(2 "B.Cu" signal "BOTTOM")
		(9 "F.Adhes" user "F.Adhesive")
		(11 "B.Adhes" user "B.Adhesive")
		(13 "F.Paste" user "Package Geometry/Pastemask Top")
		(15 "B.Paste" user "Package Geometry/Pastemask Bottom")
		(5 "F.SilkS" user "Ref Des/Silkscreen Top")
		(7 "B.SilkS" user "Ref Des/Silkscreen Bottom")
		(1 "F.Mask" user "Board Geometry/Soldermask Top")
		(3 "B.Mask" user "Board Geometry/Soldermask Bottom")
		(17 "Dwgs.User" user "User.Drawings")
		(19 "Cmts.User" user "User.Comments")
		(21 "Eco1.User" user "User.Eco1")
		(23 "Eco2.User" user "User.Eco2")
		(25 "Edge.Cuts" user "Board Geometry/Outline")
		(27 "Margin" user)
		(31 "F.CrtYd" user "Package Geometry/Place Bound Top")
		(29 "B.CrtYd" user "Package Geometry/Place Bound Bottom")
		(35 "F.Fab" user "Ref Des/Assembly Top")
		(33 "B.Fab" user "Ref Des/Assembly Bottom")
	)
	(footprint ""
		(layer "F.Cu")
		(at 187.7695 -165.056566)
		(property "Reference" "R1279"
			(at -1.672844 5.279136 0)
			(unlocked yes)
			(layer "F.SilkS")
			(effects
				(font
					(size 0.7874 0.5842)
					(thickness 0.1524)
				)
				(justify left)
			)
		)
		(property "Value" ""
			(at 0 0 0)
			(layer "F.Fab")
			(effects
				(font
					(size 1.27 1.27)
				)
			)
		)
		(duplicate_pad_numbers_are_jumpers no)
		(fp_line
			(start -0.7874 -0.4064)
			(end 0.7874 -0.4064)
			(stroke
				(width 0.1524)
				(type default)
			)
			(layer "F.SilkS")
		)
		(fp_line
			(start -0.7874 0.4064)
			(end -0.7874 -0.4064)
			(stroke
				(width 0.1524)
				(type default)
			)
			(layer "F.SilkS")
		)
		(fp_line
			(start 0.7874 -0.4064)
			(end 0.7874 0.4064)
			(stroke
				(width 0.1524)
				(type default)
			)
			(layer "F.SilkS")
		)
		(fp_line
			(start 0.7874 0.4064)
			(end -0.7874 0.4064)
			(stroke
				(width 0.1524)
				(type default)
			)
			(layer "F.SilkS")
		)
		(fp_poly
			(pts
				(xy -0.508 0.2794) (xy -0.508 0.2286) (xy -0.635 0.2286) (xy -0.635 -0.254) (xy -0.5334 -0.254)
				(xy -0.5334 -0.2794) (xy 0.5334 -0.2794) (xy 0.5334 -0.254) (xy 0.635 -0.254) (xy 0.635 0.254) (xy 0.5334 0.254)
				(xy 0.5334 0.2794)
			)
			(stroke
				(width 0)
				(type default)
			)
			(fill no)
			(layer "F.CrtYd")
		)
		(pad "1" smd rect
			(at 0.40005 0)
			(size 0.4572 0.508)
			(layers "F.Cu" "F.Mask" "F.Paste")
			(net "N54134271")
		)
		(pad "2" smd rect
			(at -0.40005 0)
			(size 0.4572 0.508)
			(layers "F.Cu" "F.Mask" "F.Paste")
			(net "LAN2_P3_R")
		)
	)
	(footprint ""
		(layer "F.Cu")
		(at 114.746786 -65.40373)
		(property "Reference" "R221"
			(at 1.969516 -0.2286 0)
			(unlocked yes)
			(layer "F.SilkS")
			(effects
				(font
					(size 0.7874 0.5842)
					(thickness 0.1524)
				)
				(justify left)
			)
		)
		(property "Value" ""
			(at 0 0 0)
			(layer "F.Fab")
			(effects
				(font
					(size 1.27 1.27)
				)
			)
		)
		(duplicate_pad_numbers_are_jumpers no)
		(fp_line
			(start -0.7874 -0.4064)
			(end 0.7874 -0.4064)
			(stroke
				(width 0.1524)
				(type default)
			)
			(layer "F.SilkS")
		)
		(fp_line
			(start -0.7874 0.4064)
			(end -0.7874 -0.4064)
			(stroke
				(width 0.1524)
				(type default)
			)
			(layer "F.SilkS")
		)
		(fp_line
			(start 0.7874 -0.4064)
			(end 0.7874 0.4064)
			(stroke
				(width 0.1524)
				(type default)
			)
			(layer "F.SilkS")
		)
		(fp_line
			(start 0.7874 0.4064)
			(end -0.7874 0.4064)
			(stroke
				(width 0.1524)
				(type default)
			)
			(layer "F.SilkS")
		)
		(fp_poly
			(pts
				(xy -0.508 0.2794) (xy -0.508 0.2286) (xy -0.635 0.2286) (xy -0.635 -0.254) (xy -0.5334 -0.254)
				(xy -0.5334 -0.2794) (xy 0.5334 -0.2794) (xy 0.5334 -0.254) (xy 0.635 -0.254) (xy 0.635 0.254) (xy 0.5334 0.254)
				(xy 0.5334 0.2794)
			)
			(stroke
				(width 0)
				(type default)
			)
			(fill no)
			(layer "F.CrtYd")
		)
		(pad "1" smd rect
			(at 0.40005 0)
			(size 0.4572 0.508)
			(layers "F.Cu" "F.Mask" "F.Paste")
			(net "P1V05_NODE1")
		)
		(pad "2" smd rect
			(at -0.40005 0)
			(size 0.4572 0.508)
			(layers "F.Cu" "F.Mask" "F.Paste")
			(net "P1V05_STB_NODE1_XDP_B")
		)
	)
	(footprint ""
		(layer "F.Cu")
		(at 66.194686 -118.758462 90)
		(property "Reference" "R345"
			(at -4.988306 -0.996442 90)
			(unlocked yes)
			(layer "F.SilkS")
			(effects
				(font
					(size 0.7874 0.5842)
					(thickness 0.1524)
				)
				(justify left)
			)
		)
		(property "Value" ""
			(at 0 0 90)
			(layer "F.Fab")
			(effects
				(font
					(size 1.27 1.27)
				)
			)
		)
		(duplicate_pad_numbers_are_jumpers no)
		(fp_line
			(start 0.7874 -0.4064)
			(end 0.7874 0.4064)
			(stroke
				(width 0.1524)
				(type default)
			)
			(layer "F.SilkS")
		)
		(fp_line
			(start -0.7874 -0.4064)
			(end 0.7874 -0.4064)
			(stroke
				(width 0.1524)
				(type default)
			)
			(layer "F.SilkS")
		)
		(fp_line
			(start 0.7874 0.4064)
			(end -0.7874 0.4064)
			(stroke
				(width 0.1524)
				(type default)
			)
			(layer "F.SilkS")
		)
		(fp_line
			(start -0.7874 0.4064)
			(end -0.7874 -0.4064)
			(stroke
				(width 0.1524)
				(type default)
			)
			(layer "F.SilkS")
		)
		(fp_poly
			(pts
				(xy -0.508 0.2794) (xy -0.508 0.2286) (xy -0.635 0.2286) (xy -0.635 -0.254) (xy -0.5334 -0.254)
				(xy -0.5334 -0.2794) (xy 0.5334 -0.2794) (xy 0.5334 -0.254) (xy 0.635 -0.254) (xy 0.635 0.254) (xy 0.5334 0.254)
				(xy 0.5334 0.2794)
			)
			(stroke
				(width 0)
				(type default)
			)
			(fill no)
			(layer "F.CrtYd")
		)
		(pad "1" smd rect
			(at 0.40005 0 90)
			(size 0.4572 0.508)
			(layers "F.Cu" "F.Mask" "F.Paste")
			(net "P3V3_NODE1")
		)
		(pad "2" smd rect
			(at -0.40005 0 90)
			(size 0.4572 0.508)
			(layers "F.Cu" "F.Mask" "F.Paste")
			(net "PU_I2C_BMC_SDA")
		)
	)
	(footprint ""
		(layer "F.Cu")
		(at 33.212786 -184.2135)
		(property "Reference" "R1022"
			(at -5.280914 -5.227828 0)
			(unlocked yes)
			(layer "F.SilkS")
			(effects
				(font
					(size 0.7874 0.5842)
					(thickness 0.1524)
				)
				(justify left)
			)
		)
		(property "Value" ""
			(at 0 0 0)
			(layer "F.Fab")
			(effects
				(font
					(size 1.27 1.27)
				)
			)
		)
		(duplicate_pad_numbers_are_jumpers no)
		(fp_line
			(start -0.7874 -0.4064)
			(end 0.7874 -0.4064)
			(stroke
				(width 0.1524)
				(type default)
			)
			(layer "F.SilkS")
		)
		(fp_line
			(start -0.7874 0.4064)
			(end -0.7874 -0.4064)
			(stroke
				(width 0.1524)
				(type default)
			)
			(layer "F.SilkS")
		)
		(fp_line
			(start 0.7874 -0.4064)
			(end 0.7874 0.4064)
			(stroke
				(width 0.1524)
				(type default)
			)
			(layer "F.SilkS")
		)
		(fp_line
			(start 0.7874 0.4064)
			(end -0.7874 0.4064)
			(stroke
				(width 0.1524)
				(type default)
			)
			(layer "F.SilkS")
		)
		(fp_poly
			(pts
				(xy -0.508 0.2794) (xy -0.508 0.2286) (xy -0.635 0.2286) (xy -0.635 -0.254) (xy -0.5334 -0.254)
				(xy -0.5334 -0.2794) (xy 0.5334 -0.2794) (xy 0.5334 -0.254) (xy 0.635 -0.254) (xy 0.635 0.254) (xy 0.5334 0.254)
				(xy 0.5334 0.2794)
			)
			(stroke
				(width 0)
				(type default)
			)
			(fill no)
			(layer "F.CrtYd")
		)
		(pad "1" smd rect
			(at 0.40005 0)
			(size 0.4572 0.508)
			(layers "F.Cu" "F.Mask" "F.Paste")
			(net "P12V_AUX_EN")
		)
		(pad "2" smd rect
			(at -0.40005 0)
			(size 0.4572 0.508)
			(layers "F.Cu" "F.Mask" "F.Paste")
			(net "AGND_HSC_NODE1")
		)
	)
	(footprint ""
		(layer "F.Cu")
		(at 150.011892 -51.786028 90)
		(property "Reference" "C495"
			(at 16.091154 27.12847 90)
			(unlocked yes)
			(layer "F.SilkS")
			(effects
				(font
					(size 0.7874 0.5842)
					(thickness 0.1524)
				)
				(justify left)
			)
		)
		(property "Value" ""
			(at 0 0 90)
			(layer "F.Fab")
			(effects
				(font
					(size 1.27 1.27)
				)
			)
		)
		(duplicate_pad_numbers_are_jumpers no)
		(fp_line
			(start 0.7874 -0.4064)
			(end 0.7874 0.4064)
			(stroke
				(width 0.1524)
				(type default)
			)
			(layer "F.SilkS")
		)
		(fp_line
			(start -0.7874 -0.4064)
			(end 0.7874 -0.4064)
			(stroke
				(width 0.1524)
				(type default)
			)
			(layer "F.SilkS")
		)
		(fp_line
			(start 0 0.381)
			(end 0 -0.381)
			(stroke
				(width 0.1524)
				(type default)
			)
			(layer "F.SilkS")
		)
		(fp_line
			(start 0.7874 0.4064)
			(end -0.7874 0.4064)
			(stroke
				(width 0.1524)
				(type default)
			)
			(layer "F.SilkS")
		)
		(fp_line
			(start -0.7874 0.4064)
			(end -0.7874 -0.4064)
			(stroke
				(width 0.1524)
				(type default)
			)
			(layer "F.SilkS")
		)
		(fp_poly
			(pts
				(xy -0.5334 0.254) (xy -0.635 0.254) (xy -0.635 0.2286) (xy -0.635 -0.254) (xy -0.5334 -0.254) (xy -0.5334 -0.2794)
				(xy 0.5334 -0.2794) (xy 0.5334 -0.254) (xy 0.635 -0.254) (xy 0.635 0.254) (xy 0.5334 0.254) (xy 0.5334 0.2794)
				(xy -0.508 0.2794) (xy -0.5334 0.2794)
			)
			(stroke
				(width 0)
				(type default)
			)
			(fill no)
			(layer "F.CrtYd")
		)
		(pad "1" smd rect
			(at 0.40005 0 90)
			(size 0.4572 0.508)
			(layers "F.Cu" "F.Mask" "F.Paste")
			(net "SATA_P7")
		)
		(pad "2" smd rect
			(at -0.40005 0 90)
			(size 0.4572 0.508)
			(layers "F.Cu" "F.Mask" "F.Paste")
			(net "GND")
		)
	)
	(footprint ""
		(layer "F.Cu")
		(at 171.225972 -53.104542 -90)
		(property "Reference" "CE3"
			(at 3.443224 4.27101 90)
			(unlocked yes)
			(layer "F.SilkS")
			(effects
				(font
					(size 0.7874 0.5842)
					(thickness 0.1524)
				)
				(justify left)
			)
		)
		(property "Value" ""
			(at 0 0 270)
			(layer "F.Fab")
			(effects
				(font
					(size 1.27 1.27)
				)
			)
		)
		(duplicate_pad_numbers_are_jumpers no)
		(fp_line
			(start -2.750058 2.750058)
			(end 2.750058 2.750058)
			(stroke
				(width 0.1524)
				(type default)
			)
			(layer "F.SilkS")
		)
		(fp_line
			(start 2.750058 2.750058)
			(end 2.750058 -1.734058)
			(stroke
				(width 0.1524)
				(type default)
			)
			(layer "F.SilkS")
		)
		(fp_line
			(start -2.750058 -1.734058)
			(end -2.750058 2.750058)
			(stroke
				(width 0.1524)
				(type default)
			)
			(layer "F.SilkS")
		)
		(fp_line
			(start 2.750058 -1.734058)
			(end 1.734058 -2.750058)
			(stroke
				(width 0.1524)
				(type default)
			)
			(layer "F.SilkS")
		)
		(fp_line
			(start -1.734058 -2.750058)
			(end -2.750058 -1.734058)
			(stroke
				(width 0.1524)
				(type default)
			)
			(layer "F.SilkS")
		)
		(fp_line
			(start 1.734058 -2.750058)
			(end -1.734058 -2.750058)
			(stroke
				(width 0.1524)
				(type default)
			)
			(layer "F.SilkS")
		)
		(fp_poly
			(pts
				(xy 2.750058 2.750058) (xy 0.8509 2.750058) (xy 0.8509 3.761994) (xy -0.8509 3.761994) (xy -0.8509 2.750058)
				(xy -2.750058 2.750058) (xy -2.750058 -2.750058) (xy -0.8509 -2.750058) (xy -0.8509 -3.761994) (xy 0.8509 -3.761994)
				(xy 0.8509 -2.750058) (xy 2.750058 -2.750058)
			)
			(stroke
				(width 0)
				(type default)
			)
			(fill no)
			(layer "F.CrtYd")
		)
		(fp_line
			(start -2.750058 2.750058)
			(end 2.750058 2.750058)
			(stroke
				(width 0.1)
				(type default)
			)
			(layer "F.Fab")
		)
		(fp_line
			(start 2.750058 2.750058)
			(end 2.750058 -2.750058)
			(stroke
				(width 0.1)
				(type default)
			)
			(layer "F.Fab")
		)
		(fp_line
			(start -2.750058 -2.750058)
			(end -2.750058 2.750058)
			(stroke
				(width 0.1)
				(type default)
			)
			(layer "F.Fab")
		)
		(fp_line
			(start 2.750058 -2.750058)
			(end -2.750058 -2.750058)
			(stroke
				(width 0.1)
				(type default)
			)
			(layer "F.Fab")
		)
		(fp_text user "2"
			(at 0.027432 4.2164 0)
			(unlocked yes)
			(layer "F.SilkS")
			(effects
				(font
					(size 0.635 0.4064)
					(thickness 0.1524)
				)
			)
		)
		(fp_text user "+"
			(at -1.741678 -3.056128 0)
			(unlocked yes)
			(layer "F.SilkS")
			(effects
				(font
					(size 1.6002 1.1938)
					(thickness 0.1524)
				)
				(justify left)
			)
		)
		(fp_text user "1"
			(at 0.342138 -4.167124 0)
			(unlocked yes)
			(layer "F.SilkS")
			(effects
				(font
					(size 0.635 0.4064)
					(thickness 0.1524)
				)
			)
		)
		(fp_text user "2"
			(at -0.041148 4.2164 0)
			(unlocked yes)
			(layer "F.Fab")
			(effects
				(font
					(size 0.7874 0.5842)
					(thickness 0.000001)
				)
			)
		)
		(fp_text user "1"
			(at -0.041148 -4.064 0)
			(unlocked yes)
			(layer "F.Fab")
			(effects
				(font
					(size 0.7874 0.5842)
					(thickness 0.000001)
				)
			)
		)
		(fp_text user "+"
			(at -0.8001 -4.89585 270)
			(unlocked yes)
			(layer "F.Fab")
			(effects
				(font
					(size 1.905 1.4224)
					(thickness 0.000001)
				)
				(justify left)
			)
		)
		(pad "1" smd oval
			(at 0 -2.199894 90)
			(size 1.6002 3.0226)
			(layers "F.Cu" "F.Mask" "F.Paste")
			(net "USBPWR_P1")
		)
		(pad "2" smd oval
			(at 0 2.199894 90)
			(size 1.6002 3.0226)
			(layers "F.Cu" "F.Mask" "F.Paste")
			(net "GND")
		)
	)
	(footprint ""
		(layer "F.Cu")
		(at 13.053568 -125.62078)
		(property "Reference" "PC58"
			(at -4.324096 -0.442976 0)
			(unlocked yes)
			(layer "F.SilkS")
			(effects
				(font
					(size 0.7874 0.5842)
					(thickness 0.1524)
				)
				(justify left)
			)
		)
		(property "Value" ""
			(at 0 0 0)
			(layer "F.Fab")
			(effects
				(font
					(size 1.27 1.27)
				)
			)
		)
		(duplicate_pad_numbers_are_jumpers no)
		(fp_line
			(start -0.7874 -0.4064)
			(end 0.7874 -0.4064)
			(stroke
				(width 0.1524)
				(type default)
			)
			(layer "F.SilkS")
		)
		(fp_line
			(start -0.7874 0.4064)
			(end -0.7874 -0.4064)
			(stroke
				(width 0.1524)
				(type default)
			)
			(layer "F.SilkS")
		)
		(fp_line
			(start 0 0.381)
			(end 0 -0.381)
			(stroke
				(width 0.1524)
				(type default)
			)
			(layer "F.SilkS")
		)
		(fp_line
			(start 0.7874 -0.4064)
			(end 0.7874 0.4064)
			(stroke
				(width 0.1524)
				(type default)
			)
			(layer "F.SilkS")
		)
		(fp_line
			(start 0.7874 0.4064)
			(end -0.7874 0.4064)
			(stroke
				(width 0.1524)
				(type default)
			)
			(layer "F.SilkS")
		)
		(fp_poly
			(pts
				(xy -0.5334 0.254) (xy -0.635 0.254) (xy -0.635 0.2286) (xy -0.635 -0.254) (xy -0.5334 -0.254) (xy -0.5334 -0.2794)
				(xy 0.5334 -0.2794) (xy 0.5334 -0.254) (xy 0.635 -0.254) (xy 0.635 0.254) (xy 0.5334 0.254) (xy 0.5334 0.2794)
				(xy -0.508 0.2794) (xy -0.5334 0.2794)
			)
			(stroke
				(width 0)
				(type default)
			)
			(fill no)
			(layer "F.CrtYd")
		)
		(pad "1" smd rect
			(at 0.40005 0)
			(size 0.4572 0.508)
			(layers "F.Cu" "F.Mask" "F.Paste")
			(net "SW_P1V05_NODE1_VIN_FLT")
		)
		(pad "2" smd rect
			(at -0.40005 0)
			(size 0.4572 0.508)
			(layers "F.Cu" "F.Mask" "F.Paste")
			(net "GND")
		)
	)
	(footprint ""
		(layer "F.Cu")
		(at 163.261294 -123.07062 180)
		(property "Reference" "Q24"
			(at 5.640324 1.886712 0)
			(unlocked yes)
			(layer "F.SilkS")
			(effects
				(font
					(size 0.7874 0.5842)
					(thickness 0.1524)
				)
				(justify left)
			)
		)
		(property "Value" ""
			(at 0 0 180)
			(layer "F.Fab")
			(effects
				(font
					(size 1.27 1.27)
				)
			)
		)
		(duplicate_pad_numbers_are_jumpers no)
		(fp_line
			(start 2.584196 2.48412)
			(end -0.5842 2.48412)
			(stroke
				(width 0.1524)
				(type default)
			)
			(layer "F.SilkS")
		)
		(fp_line
			(start 2.584196 -0.5842)
			(end 2.584196 2.48412)
			(stroke
				(width 0.1524)
				(type default)
			)
			(layer "F.SilkS")
		)
		(fp_line
			(start -0.5842 2.48412)
			(end -0.5842 -0.5842)
			(stroke
				(width 0.1524)
				(type default)
			)
			(layer "F.SilkS")
		)
		(fp_line
			(start -0.5842 -0.5842)
			(end 2.584196 -0.5842)
			(stroke
				(width 0.1524)
				(type default)
			)
			(layer "F.SilkS")
		)
		(fp_poly
			(pts
				(xy -0.508 -0.4572) (xy 0.299974 -0.4572) (xy 0.299974 -0.54991) (xy 1.700022 -0.54991) (xy 1.700022 0.49276)
				(xy 2.507996 0.49276) (xy 2.507996 1.40716) (xy 1.700022 1.40716) (xy 1.700022 2.450084) (xy 0.299974 2.450084)
				(xy 0.299974 2.35712) (xy -0.508 2.35712)
			)
			(stroke
				(width 0)
				(type default)
			)
			(fill no)
			(layer "F.CrtYd")
		)
		(fp_line
			(start 1.700022 2.450084)
			(end 0.299974 2.450084)
			(stroke
				(width 0.1)
				(type default)
			)
			(layer "F.Fab")
		)
		(fp_line
			(start 1.700022 -0.54991)
			(end 1.700022 2.450084)
			(stroke
				(width 0.1)
				(type default)
			)
			(layer "F.Fab")
		)
		(fp_line
			(start 0.299974 2.450084)
			(end 0.299974 -0.54991)
			(stroke
				(width 0.1)
				(type default)
			)
			(layer "F.Fab")
		)
		(fp_line
			(start 0.299974 -0.54991)
			(end 1.700022 -0.54991)
			(stroke
				(width 0.1)
				(type default)
			)
			(layer "F.Fab")
		)
		(fp_text user "C"
			(at 3.233928 0.406908 0)
			(unlocked yes)
			(layer "F.SilkS")
			(effects
				(font
					(size 0.635 0.4064)
					(thickness 0.1524)
				)
				(justify left)
			)
		)
		(fp_text user "B"
			(at -0.737108 -0.099314 0)
			(unlocked yes)
			(layer "F.SilkS")
			(effects
				(font
					(size 0.635 0.4064)
					(thickness 0.1524)
				)
				(justify left)
			)
		)
		(fp_text user "E"
			(at -0.801624 1.227328 0)
			(unlocked yes)
			(layer "F.SilkS")
			(effects
				(font
					(size 0.635 0.4064)
					(thickness 0.1524)
				)
				(justify left)
			)
		)
		(fp_text user "C"
			(at 2.8702 0.99187 180)
			(unlocked yes)
			(layer "F.Fab")
			(effects
				(font
					(size 0.7874 0.5842)
					(thickness 0.000001)
				)
				(justify left)
			)
		)
		(fp_text user "B"
			(at -1.5494 0.00127 180)
			(unlocked yes)
			(layer "F.Fab")
			(effects
				(font
					(size 0.7874 0.5842)
					(thickness 0.000001)
				)
				(justify left)
			)
		)
		(fp_text user "E"
			(at -1.5748 1.95707 180)
			(unlocked yes)
			(layer "F.Fab")
			(effects
				(font
					(size 0.7874 0.5842)
					(thickness 0.000001)
				)
				(justify left)
			)
		)
		(pad "B" smd rect
			(at 0 0 270)
			(size 0.8128 0.9144)
			(layers "F.Cu" "F.Mask" "F.Paste")
			(net "FM_NODE1_DDR3_DRAM_POK_R_L")
		)
		(pad "C" smd rect
			(at 1.999996 0.94996 270)
			(size 0.8128 0.9144)
			(layers "F.Cu" "F.Mask" "F.Paste")
			(net "PWRGD_NODE1_DDR3_DRAM_POK")
		)
		(pad "E" smd rect
			(at 0 1.89992 270)
			(size 0.8128 0.9144)
			(layers "F.Cu" "F.Mask" "F.Paste")
			(net "GND")
		)
	)
)
